# T6G (Grand Teton) — schematic netlist excerpt (pin names and nets, part order shuffled) for the footprints in the layout excerpt that follows; sources: Cadence DE-HDL packaged netlist, KiCad conversion of 04192023_DAF0TMB3IC0_F0TG_MB_C_brd_V02_OCP.brd

PC500_1  Q_CAP  22UF 4V 20% X6S  pkg C0805  page 194 : A = PVDDCR_CPU0_P0 ; B = GND
PR6625  Q_RES  499 1% CHIP  pkg 0603LF  page 365 : A = P0V9_CPU1_RT_2D ; B = GND
R6821  Q_RES  0 5% CHIP  pkg 0201LF  page 277 : A = NCF_CPU0_P0_GND ; B = GND
C794  Q_CAP  0.1UF 10V 10% X7S  pkg C0201  page 301 : A = P0V9_CPU0_RT2_2A_2D ; B = GND

(kicad_pcb
	(version 20260206)
	(generator "pcbnew")
	(generator_version "10.0")
	(general
		(thickness 1.6)
		(legacy_teardrops no)
	)
	(paper "A4")
	(title_block
		(title "04192023_DAF0TMB3IC0_F0TG_MB_C_brd_V02_OCP.brd")
		(comment 1 "Grand Teton / footprints 6039-6042 of 8354")
	)
	(layers
		(0 "F.Cu" signal "TOP")
		(4 "In1.Cu" signal "GND")
		(6 "In2.Cu" signal "IN1")
		(8 "In3.Cu" signal "GND1")
		(10 "In4.Cu" signal "IN2")
		(12 "In5.Cu" signal "GND2")
		(14 "In6.Cu" signal "IN3")
		(16 "In7.Cu" signal "GND3")
		(18 "In8.Cu" signal "VCC")
		(20 "In9.Cu" signal "VCC1")
		(22 "In10.Cu" signal "GND4")
		(24 "In11.Cu" signal "IN4")
		(26 "In12.Cu" signal "GND5")
		(28 "In13.Cu" signal "IN5")
		(30 "In14.Cu" signal "GND6")
		(32 "In15.Cu" signal "IN6")
		(34 "In16.Cu" signal "GND7")
		(2 "B.Cu" signal "BOTTOM")
		(9 "F.Adhes" user "F.Adhesive")
		(11 "B.Adhes" user "B.Adhesive")
		(13 "F.Paste" user "Package Geometry/Pastemask Top")
		(15 "B.Paste" user "Package Geometry/Pastemask Bottom")
		(5 "F.SilkS" user "Ref Des/Silkscreen Top")
		(7 "B.SilkS" user "Ref Des/Silkscreen Bottom")
		(1 "F.Mask" user "Board Geometry/Soldermask Top")
		(3 "B.Mask" user "Board Geometry/Soldermask Bottom")
		(17 "Dwgs.User" user "User.Drawings")
		(19 "Cmts.User" user "User.Comments")
		(21 "Eco1.User" user "User.Eco1")
		(23 "Eco2.User" user "User.Eco2")
		(25 "Edge.Cuts" user "Board Geometry/Outline")
		(27 "Margin" user)
		(31 "F.CrtYd" user "Package Geometry/Place Bound Top")
		(29 "B.CrtYd" user "Package Geometry/Place Bound Bottom")
		(35 "F.Fab" user "Ref Des/Assembly Top")
		(33 "B.Fab" user "Ref Des/Assembly Bottom")
	)
	(footprint ""
		(layer "B.Cu")
		(at 7.62 -383.032 -90)
		(property "Reference" "PR6625"
			(at 0 0 90)
			(layer "B.SilkS")
			(hide yes)
			(effects
				(font
					(size 1.27 1.27)
				)
				(justify mirror)
			)
		)
		(property "Value" ""
			(at 0 0 90)
			(layer "B.Fab")
			(effects
				(font
					(size 1.27 1.27)
				)
				(justify mirror)
			)
		)
		(duplicate_pad_numbers_are_jumpers no)
		(fp_line
			(start -1.2954 0.5842)
			(end 1.2954 0.5842)
			(stroke
				(width 0.1524)
				(type default)
			)
			(layer "B.SilkS")
		)
		(fp_line
			(start 1.2954 0.5842)
			(end 1.2954 -0.5842)
			(stroke
				(width 0.1524)
				(type default)
			)
			(layer "B.SilkS")
		)
		(fp_line
			(start -1.2954 -0.5842)
			(end -1.2954 0.5842)
			(stroke
				(width 0.1524)
				(type default)
			)
			(layer "B.SilkS")
		)
		(fp_line
			(start 1.2954 -0.5842)
			(end -1.2954 -0.5842)
			(stroke
				(width 0.1524)
				(type default)
			)
			(layer "B.SilkS")
		)
		(fp_line
			(start -0.8636 0.4572)
			(end 0.8636 0.4572)
			(stroke
				(width 0.1)
				(type default)
			)
			(layer "B.Fab")
		)
		(fp_line
			(start 0.8636 0.4572)
			(end 0.8636 0.4318)
			(stroke
				(width 0.1)
				(type default)
			)
			(layer "B.Fab")
		)
		(fp_line
			(start 0.8636 0.4318)
			(end 0.8636 0.4064)
			(stroke
				(width 0.1)
				(type default)
			)
			(layer "B.Fab")
		)
		(fp_line
			(start -1.1938 0.4064)
			(end -0.8636 0.4064)
			(stroke
				(width 0.1)
				(type default)
			)
			(layer "B.Fab")
		)
		(fp_line
			(start -0.8636 0.4064)
			(end -0.8636 0.4572)
			(stroke
				(width 0.1)
				(type default)
			)
			(layer "B.Fab")
		)
		(fp_line
			(start 0.8636 0.4064)
			(end 1.1938 0.4064)
			(stroke
				(width 0.1)
				(type default)
			)
			(layer "B.Fab")
		)
		(fp_line
			(start 1.1938 0.4064)
			(end 1.1938 -0.406654)
			(stroke
				(width 0.1)
				(type default)
			)
			(layer "B.Fab")
		)
		(fp_line
			(start -1.1938 -0.406654)
			(end -1.1938 0.4064)
			(stroke
				(width 0.1)
				(type default)
			)
			(layer "B.Fab")
		)
		(fp_line
			(start -0.8636 -0.406654)
			(end -1.1938 -0.406654)
			(stroke
				(width 0.1)
				(type default)
			)
			(layer "B.Fab")
		)
		(fp_line
			(start 0.8636 -0.406654)
			(end 0.8636 -0.4572)
			(stroke
				(width 0.1)
				(type default)
			)
			(layer "B.Fab")
		)
		(fp_line
			(start 1.1938 -0.406654)
			(end 0.8636 -0.406654)
			(stroke
				(width 0.1)
				(type default)
			)
			(layer "B.Fab")
		)
		(fp_line
			(start -0.8636 -0.4572)
			(end -0.8636 -0.406654)
			(stroke
				(width 0.1)
				(type default)
			)
			(layer "B.Fab")
		)
		(fp_line
			(start 0.8636 -0.4572)
			(end -0.8636 -0.4572)
			(stroke
				(width 0.1)
				(type default)
			)
			(layer "B.Fab")
		)
		(pad "1" smd rect
			(at 0.7366 0 180)
			(size 0.7112 0.8128)
			(layers "B.Cu" "B.Mask" "B.Paste")
			(net "P0V9_CPU1_RT_2D")
		)
		(pad "2" smd rect
			(at -0.7366 0 180)
			(size 0.7112 0.8128)
			(layers "B.Cu" "B.Mask" "B.Paste")
			(net "GND")
		)
	)
	(footprint ""
		(layer "B.Cu")
		(at 347.624908 -169.787062 90)
		(property "Reference" "PC500_1"
			(at 0 0 90)
			(layer "B.SilkS")
			(hide yes)
			(effects
				(font
					(size 1.27 1.27)
				)
				(justify mirror)
			)
		)
		(property "Value" ""
			(at 0 0 90)
			(layer "B.Fab")
			(effects
				(font
					(size 1.27 1.27)
				)
				(justify mirror)
			)
		)
		(duplicate_pad_numbers_are_jumpers no)
		(fp_line
			(start 1.524 -0.762)
			(end -1.524 -0.762)
			(stroke
				(width 0.1524)
				(type default)
			)
			(layer "B.SilkS")
		)
		(fp_line
			(start -1.524 -0.762)
			(end -1.524 0.762)
			(stroke
				(width 0.1524)
				(type default)
			)
			(layer "B.SilkS")
		)
		(fp_line
			(start 1.524 0.762)
			(end 1.524 -0.762)
			(stroke
				(width 0.1524)
				(type default)
			)
			(layer "B.SilkS")
		)
		(fp_line
			(start -1.524 0.762)
			(end 1.524 0.762)
			(stroke
				(width 0.1524)
				(type default)
			)
			(layer "B.SilkS")
		)
		(fp_line
			(start 1.1049 -0.724916)
			(end 1.1049 0.724916)
			(stroke
				(width 0.1)
				(type default)
			)
			(layer "B.Fab")
		)
		(fp_line
			(start -1.1049 -0.724916)
			(end 1.1049 -0.724916)
			(stroke
				(width 0.1)
				(type default)
			)
			(layer "B.Fab")
		)
		(fp_line
			(start 1.1049 0.724916)
			(end -1.1049 0.724916)
			(stroke
				(width 0.1)
				(type default)
			)
			(layer "B.Fab")
		)
		(fp_line
			(start -1.1049 0.724916)
			(end -1.1049 -0.724916)
			(stroke
				(width 0.1)
				(type default)
			)
			(layer "B.Fab")
		)
		(pad "1" smd rect
			(at 0.889 0 90)
			(size 1.016 1.27)
			(layers "B.Cu" "B.Mask" "B.Paste")
			(net "PVDDCR_CPU0_P0")
		)
		(pad "2" smd rect
			(at -0.889 0 90)
			(size 1.016 1.27)
			(layers "B.Cu" "B.Mask" "B.Paste")
			(net "GND")
		)
	)
	(footprint ""
		(layer "B.Cu")
		(at 326.052942 -391.2616 180)
		(property "Reference" "R6821"
			(at 0 0 0)
			(layer "B.SilkS")
			(hide yes)
			(effects
				(font
					(size 1.27 1.27)
				)
				(justify mirror)
			)
		)
		(property "Value" ""
			(at 0 0 0)
			(layer "B.Fab")
			(effects
				(font
					(size 1.27 1.27)
				)
				(justify mirror)
			)
		)
		(duplicate_pad_numbers_are_jumpers no)
		(fp_line
			(start 0.32512 0.175006)
			(end 0.32512 -0.175006)
			(stroke
				(width 0.1)
				(type default)
			)
			(layer "B.Fab")
		)
		(fp_line
			(start 0.32512 -0.175006)
			(end -0.32512 -0.175006)
			(stroke
				(width 0.1)
				(type default)
			)
			(layer "B.Fab")
		)
		(fp_line
			(start -0.32512 0.175006)
			(end 0.32512 0.175006)
			(stroke
				(width 0.1)
				(type default)
			)
			(layer "B.Fab")
		)
		(fp_line
			(start -0.32512 -0.175006)
			(end -0.32512 0.175006)
			(stroke
				(width 0.1)
				(type default)
			)
			(layer "B.Fab")
		)
		(pad "1" smd rect
			(at 0.2667 0)
			(size 0.3048 0.381)
			(layers "B.Cu" "B.Mask" "B.Paste")
			(net "NCF_CPU0_P0_GND")
		)
		(pad "2" smd rect
			(at -0.2667 0 180)
			(size 0.3048 0.381)
			(layers "B.Cu" "B.Mask" "B.Paste")
			(net "GND")
		)
	)
	(footprint ""
		(layer "B.Cu")
		(at 416.346132 -396.393162 -90)
		(property "Reference" "C794"
			(at 0 0 90)
			(layer "B.SilkS")
			(hide yes)
			(effects
				(font
					(size 1.27 1.27)
				)
				(justify mirror)
			)
		)
		(property "Value" ""
			(at 0 0 90)
			(layer "B.Fab")
			(effects
				(font
					(size 1.27 1.27)
				)
				(justify mirror)
			)
		)
		(duplicate_pad_numbers_are_jumpers no)
		(fp_line
			(start -0.299974 0.150114)
			(end 0.299974 0.150114)
			(stroke
				(width 0.1)
				(type default)
			)
			(layer "B.Fab")
		)
		(fp_line
			(start 0.299974 0.150114)
			(end 0.299974 -0.150114)
			(stroke
				(width 0.1)
				(type default)
			)
			(layer "B.Fab")
		)
		(fp_line
			(start -0.299974 -0.150114)
			(end -0.299974 0.150114)
			(stroke
				(width 0.1)
				(type default)
			)
			(layer "B.Fab")
		)
		(fp_line
			(start 0.299974 -0.150114)
			(end -0.299974 -0.150114)
			(stroke
				(width 0.1)
				(type default)
			)
			(layer "B.Fab")
		)
		(pad "1" smd rect
			(at 0.2667 0 90)
			(size 0.3048 0.381)
			(layers "B.Cu" "B.Mask" "B.Paste")
			(net "P0V9_CPU0_RT2_2A_2D")
		)
		(pad "2" smd rect
			(at -0.2667 0 90)
			(size 0.3048 0.381)
			(layers "B.Cu" "B.Mask" "B.Paste")
			(net "GND")
		)
	)
)
